(kicad_pcb
	(version 20241229)
	(generator "pcbnew")
	(generator_version "9.0")
	(general
		(thickness 1.61)
		(legacy_teardrops no)
	)
	(paper "A3")
	(title_block
		(title "SO-DIMM DDR5 Tester")
		(date "2025-11-26")
		(rev "1.3.0")
		(comment 9 "footprints 276-281 of 627")
	)
	(layers
		(0 "F.Cu" signal)
		(4 "In1.Cu" power)
		(6 "In2.Cu" mixed)
		(8 "In3.Cu" power)
		(10 "In4.Cu" mixed)
		(12 "In5.Cu" power)
		(14 "In6.Cu" mixed)
		(16 "In7.Cu" power)
		(18 "In8.Cu" power)
		(20 "In9.Cu" mixed)
		(22 "In10.Cu" power)
		(2 "B.Cu" signal)
		(9 "F.Adhes" user "F.Adhesive")
		(11 "B.Adhes" user "B.Adhesive")
		(13 "F.Paste" user)
		(15 "B.Paste" user)
		(5 "F.SilkS" user "F.Silkscreen")
		(7 "B.SilkS" user "B.Silkscreen")
		(1 "F.Mask" user)
		(3 "B.Mask" user)
		(17 "Dwgs.User" user "User.Drawings")
		(19 "Cmts.User" user "User.Comments")
		(21 "Eco1.User" user "User.Eco1")
		(23 "Eco2.User" user "User.Eco2")
		(25 "Edge.Cuts" user)
		(27 "Margin" user)
		(31 "F.CrtYd" user "F.Courtyard")
		(29 "B.CrtYd" user "B.Courtyard")
		(35 "F.Fab" user)
		(33 "B.Fab" user)
	)
	(footprint "antmicro-footprints:R_0402_1005Metric"
		(layer "F.Cu")
		(at 103.05 184.785 90)
		(descr "Resistor SMD 0402")
		(tags "resistor SMD 0402")
		(property "Reference" "R93"
			(at -1.122484 -0.772697 90)
			(layer "F.SilkS")
			(hide yes)
			(effects
				(font
					(size 0.7 0.7)
					(thickness 0.15)
				)
				(justify left bottom)
			)
		)
		(property "Value" "R_0R_0402"
			(at -1.011843 1.772047 90)
			(layer "F.Fab")
			(effects
				(font
					(size 0.7 0.7)
					(thickness 0.15)
				)
				(justify left bottom)
			)
		)
		(property "Datasheet" "https://industrial.panasonic.com/cdbs/www-data/pdf/RDA0000/AOA0000C301.pdf"
			(at 0 0 90)
			(layer "F.Fab")
			(hide yes)
			(effects
				(font
					(size 1.27 1.27)
					(thickness 0.15)
				)
			)
		)
		(property "Author" "Antmicro"
			(at 287.835 81.735 0)
			(layer "F.Fab")
			(hide yes)
			(effects
				(font
					(size 1 1)
					(thickness 0.15)
				)
			)
		)
		(property "Current" "1A"
			(at 287.835 81.735 0)
			(layer "F.Fab")
			(hide yes)
			(effects
				(font
					(size 1 1)
					(thickness 0.15)
				)
			)
		)
		(property "License" "Apache-2.0"
			(at 287.835 81.735 0)
			(layer "F.Fab")
			(hide yes)
			(effects
				(font
					(size 1 1)
					(thickness 0.15)
				)
			)
		)
		(property "MPN" "ERJ2GE0R00X"
			(at 287.835 81.735 0)
			(layer "F.Fab")
			(hide yes)
			(effects
				(font
					(size 1 1)
					(thickness 0.15)
				)
			)
		)
		(property "Manufacturer" "Panasonic"
			(at 287.835 81.735 0)
			(layer "F.Fab")
			(hide yes)
			(effects
				(font
					(size 1 1)
					(thickness 0.15)
				)
			)
		)
		(property "Tolerance" ""
			(at 287.835 81.735 0)
			(layer "F.Fab")
			(hide yes)
			(effects
				(font
					(size 1 1)
					(thickness 0.15)
				)
			)
		)
		(property "Val" "0R"
			(at 287.835 81.735 0)
			(layer "F.Fab")
			(hide yes)
			(effects
				(font
					(size 1 1)
					(thickness 0.15)
				)
			)
		)
		(sheetname "/Debug FTDI/")
		(sheetfile "debug-ftdi.kicad_sch")
		(attr smd)
		(fp_rect
			(start -0.93 -0.47)
			(end 0.93 0.47)
			(stroke
				(width 0.05)
				(type solid)
			)
			(fill no)
			(layer "F.CrtYd")
		)
		(fp_rect
			(start -0.5 -0.25)
			(end 0.5 0.25)
			(stroke
				(width 0.15)
				(type solid)
			)
			(fill no)
			(layer "F.Fab")
		)
		(pad "1" smd roundrect
			(at -0.485 0 90)
			(size 0.59 0.64)
			(layers "F.Cu" "F.Mask" "F.Paste")
			(roundrect_rratio 0.25)
			(net 672 "/Debug FTDI/FTDI.SDA")
			(pintype "passive")
		)
		(pad "2" smd roundrect
			(at 0.485 0 90)
			(size 0.59 0.64)
			(layers "F.Cu" "F.Mask" "F.Paste")
			(roundrect_rratio 0.25)
			(net 43 "/Debug FTDI/FTDI_SDA_IN")
			(pintype "passive")
		)
	)
	(footprint "antmicro-footprints:TP_SMD_1mm"
		(layer "F.Cu")
		(at 186.4 182.1)
		(property "Reference" "TP15"
			(at 0 -0.731898 0)
			(layer "F.SilkS")
			(hide yes)
			(effects
				(font
					(size 0.7 0.7)
					(thickness 0.15)
				)
				(justify left bottom)
			)
		)
		(property "Value" "TP_1mm_SMD"
			(at 0 1.4 0)
			(layer "F.Fab")
			(effects
				(font
					(size 0.7 0.7)
					(thickness 0.15)
				)
				(justify left bottom)
			)
		)
		(property "Author" "Antmicro"
			(at 0 0 0)
			(layer "F.Fab")
			(hide yes)
			(effects
				(font
					(size 1 1)
					(thickness 0.15)
				)
			)
		)
		(property "License" "Apache-2.0"
			(at 0 0 0)
			(layer "F.Fab")
			(hide yes)
			(effects
				(font
					(size 1 1)
					(thickness 0.15)
				)
			)
		)
		(property "MPN" ""
			(at 0 0 0)
			(layer "F.Fab")
			(hide yes)
			(effects
				(font
					(size 1 1)
					(thickness 0.15)
				)
			)
		)
		(property "Manufacturer" ""
			(at 0 0 0)
			(layer "F.Fab")
			(hide yes)
			(effects
				(font
					(size 1 1)
					(thickness 0.15)
				)
			)
		)
		(sheetname "/Supply/")
		(sheetfile "supply.kicad_sch")
		(attr exclude_from_pos_files)
		(pad "1" smd circle
			(at 0 0)
			(size 1 1)
			(layers "F.Cu" "F.Mask")
			(net 188 "+1V8")
			(pinfunction "1")
			(pintype "passive")
		)
	)
	(footprint "antmicro-footprints:SW_DIP_SPSTx02_Slide_Copal_CVS-02xB_W5.9mm_P1mm"
		(layer "F.Cu")
		(at 118.3 193.2)
		(descr "SMD 2x-dip-switch SPST Copal_CVS-02xB, Slide, row spacing 5.9 mm")
		(tags "SMD DIP Switch SPST Slide 5.9mm")
		(property "Reference" "SW6"
			(at 1.8 3.3 0)
			(layer "F.SilkS")
			(effects
				(font
					(size 0.7 0.7)
					(thickness 0.15)
				)
				(justify left bottom)
			)
		)
		(property "Value" "SW_CVS-02B"
			(at 0 2.91 0)
			(layer "F.Fab")
			(effects
				(font
					(size 0.7 0.7)
					(thickness 0.15)
				)
				(justify left bottom)
			)
		)
		(property "Datasheet" "https://www.mouser.com/datasheet/2/972/cvs-1827291.pdf"
			(at 0 0 0)
			(layer "F.Fab")
			(hide yes)
			(effects
				(font
					(size 1.27 1.27)
					(thickness 0.15)
				)
			)
		)
		(property "Author" "Antmicro"
			(at 0 0 0)
			(layer "F.Fab")
			(hide yes)
			(effects
				(font
					(size 1 1)
					(thickness 0.15)
				)
			)
		)
		(property "License" "Apache-2.0"
			(at 0 0 0)
			(layer "F.Fab")
			(hide yes)
			(effects
				(font
					(size 1 1)
					(thickness 0.15)
				)
			)
		)
		(property "MPN" "CVS-02B"
			(at 0 0 0)
			(layer "F.Fab")
			(hide yes)
			(effects
				(font
					(size 1 1)
					(thickness 0.15)
				)
			)
		)
		(property "Manufacturer" "Nidec Components"
			(at 0 0 0)
			(layer "F.Fab")
			(hide yes)
			(effects
				(font
					(size 1 1)
					(thickness 0.15)
				)
			)
		)
		(property ki_fp_filters "SW?DIP?x2*")
		(sheetname "/PCIe connector/")
		(sheetfile "pcie-connector.kicad_sch")
		(attr smd)
		(fp_line
			(start -1.561 -1.911)
			(end 1.56 -1.911)
			(stroke
				(width 0.15)
				(type solid)
			)
			(layer "F.SilkS")
		)
		(fp_line
			(start -1.561 1.908)
			(end 1.56 1.908)
			(stroke
				(width 0.15)
				(type solid)
			)
			(layer "F.SilkS")
		)
		(fp_circle
			(center -3.4 -1.1)
			(end -3.35 -1.06)
			(stroke
				(width 0.15)
				(type solid)
			)
			(fill yes)
			(layer "F.SilkS")
		)
		(fp_rect
			(start -3.6 -2)
			(end 3.6 2)
			(stroke
				(width 0.05)
				(type solid)
			)
			(fill no)
			(layer "F.CrtYd")
		)
		(fp_line
			(start -2.351 -0.5)
			(end -1.351 -1.5)
			(stroke
				(width 0.15)
				(type solid)
			)
			(layer "F.Fab")
		)
		(fp_line
			(start -1 -0.75)
			(end -1 -0.25)
			(stroke
				(width 0.15)
				(type solid)
			)
			(layer "F.Fab")
		)
		(fp_line
			(start -1 -0.652)
			(end -0.335 -0.652)
			(stroke
				(width 0.15)
				(type solid)
			)
			(layer "F.Fab")
		)
		(fp_line
			(start -1 -0.552)
			(end -0.335 -0.552)
			(stroke
				(width 0.15)
				(type solid)
			)
			(layer "F.Fab")
		)
		(fp_line
			(start -1 -0.452)
			(end -0.335 -0.452)
			(stroke
				(width 0.15)
				(type solid)
			)
			(layer "F.Fab")
		)
		(fp_line
			(start -1 -0.351)
			(end -0.335 -0.351)
			(stroke
				(width 0.15)
				(type solid)
			)
			(layer "F.Fab")
		)
		(fp_line
			(start -1 -0.25)
			(end 0.998 -0.25)
			(stroke
				(width 0.15)
				(type solid)
			)
			(layer "F.Fab")
		)
		(fp_line
			(start -1 0.248)
			(end -1 0.748)
			(stroke
				(width 0.15)
				(type solid)
			)
			(layer "F.Fab")
		)
		(fp_line
			(start -1 0.349)
			(end -0.335 0.349)
			(stroke
				(width 0.15)
				(type solid)
			)
			(layer "F.Fab")
		)
		(fp_line
			(start -1 0.45)
			(end -0.335 0.45)
			(stroke
				(width 0.15)
				(type solid)
			)
			(layer "F.Fab")
		)
		(fp_line
			(start -1 0.55)
			(end -0.335 0.55)
			(stroke
				(width 0.15)
				(type solid)
			)
			(layer "F.Fab")
		)
		(fp_line
			(start -1 0.65)
			(end -0.335 0.65)
			(stroke
				(width 0.15)
				(type solid)
			)
			(layer "F.Fab")
		)
		(fp_line
			(start -1 0.748)
			(end 0.998 0.748)
			(stroke
				(width 0.15)
				(type solid)
			)
			(layer "F.Fab")
		)
		(fp_line
			(start -0.335 -0.75)
			(end -0.335 -0.25)
			(stroke
				(width 0.15)
				(type solid)
			)
			(layer "F.Fab")
		)
		(fp_line
			(start -0.335 0.248)
			(end -0.335 0.748)
			(stroke
				(width 0.15)
				(type solid)
			)
			(layer "F.Fab")
		)
		(fp_line
			(start 0.998 -0.75)
			(end -1 -0.75)
			(stroke
				(width 0.15)
				(type solid)
			)
			(layer "F.Fab")
		)
		(fp_line
			(start 0.998 -0.25)
			(end 0.998 -0.75)
			(stroke
				(width 0.15)
				(type solid)
			)
			(layer "F.Fab")
		)
		(fp_line
			(start 0.998 0.248)
			(end -1 0.248)
			(stroke
				(width 0.15)
				(type solid)
			)
			(layer "F.Fab")
		)
		(fp_line
			(start 0.998 0.748)
			(end 0.998 0.248)
			(stroke
				(width 0.15)
				(type solid)
			)
			(layer "F.Fab")
		)
		(fp_rect
			(start 2.35 1.499)
			(end -2.351 -1.5)
			(stroke
				(width 0.15)
				(type solid)
			)
			(fill no)
			(layer "F.Fab")
		)
		(fp_text user "on"
			(at -1.5 0.739 90)
			(layer "F.Fab")
			(effects
				(font
					(size 0.7 0.7)
					(thickness 0.15)
				)
				(justify left bottom)
			)
		)
		(pad "1" smd rect
			(at -2.95 -0.5)
			(size 1.2 0.5)
			(layers "F.Cu" "F.Mask" "F.Paste")
			(net 229 "/PCIe connector/PRSNT#1")
			(pintype "passive")
		)
		(pad "2" smd rect
			(at -2.95 0.5)
			(size 1.2 0.5)
			(layers "F.Cu" "F.Mask" "F.Paste")
			(net 229 "/PCIe connector/PRSNT#1")
			(pintype "passive")
		)
		(pad "3" smd rect
			(at 2.95 0.5)
			(size 1.2 0.5)
			(layers "F.Cu" "F.Mask" "F.Paste")
			(net 231 "/PCIe connector/x4")
			(pintype "passive")
		)
		(pad "4" smd rect
			(at 2.95 -0.5)
			(size 1.2 0.5)
			(layers "F.Cu" "F.Mask" "F.Paste")
			(net 230 "/PCIe connector/x1")
			(pintype "passive")
		)
		(pad "SH" smd rect
			(at -2.15 -1.5)
			(size 0.7 0.7)
			(layers "F.Cu" "F.Mask" "F.Paste")
			(net 1 "GND")
			(pinfunction "SH")
			(pintype "power_in")
		)
		(pad "SH" smd rect
			(at -2.15 1.5)
			(size 0.7 0.7)
			(layers "F.Cu" "F.Mask" "F.Paste")
			(net 1 "GND")
			(pinfunction "SH")
			(pintype "power_in")
		)
		(pad "SH" smd rect
			(at 2.15 -1.5)
			(size 0.7 0.7)
			(layers "F.Cu" "F.Mask" "F.Paste")
			(net 1 "GND")
			(pinfunction "SH")
			(pintype "power_in")
		)
		(pad "SH" smd rect
			(at 2.15 1.5)
			(size 0.7 0.7)
			(layers "F.Cu" "F.Mask" "F.Paste")
			(net 1 "GND")
			(pinfunction "SH")
			(pintype "power_in")
		)
	)
	(footprint "antmicro-footprints:NetTie-2_SMD_Pad0.127mm"
		(layer "F.Cu")
		(at 198.226501 159.7 180)
		(descr "Net tie, 2 pin, 0.127mm  SMD pads")
		(tags "net tie")
		(property "Reference" "NT15"
			(at -0.128 -1.345 180)
			(layer "F.SilkS")
			(hide yes)
			(effects
				(font
					(size 0.7 0.7)
					(thickness 0.15)
				)
				(justify left bottom)
			)
		)
		(property "Value" "Net-Tie_P0.127mm"
			(at 0 1.199 180)
			(layer "F.Fab")
			(effects
				(font
					(size 0.7 0.7)
					(thickness 0.15)
				)
				(justify left bottom)
			)
		)
		(property "Author" "Antmicro"
			(at 396.453002 319.4 0)
			(layer "F.Fab")
			(hide yes)
			(effects
				(font
					(size 1 1)
					(thickness 0.15)
				)
			)
		)
		(property "License" "Apache-2.0"
			(at 396.453002 319.4 0)
			(layer "F.Fab")
			(hide yes)
			(effects
				(font
					(size 1 1)
					(thickness 0.15)
				)
			)
		)
		(property "MPN" ""
			(at 396.453002 319.4 0)
			(layer "F.Fab")
			(hide yes)
			(effects
				(font
					(size 1 1)
					(thickness 0.15)
				)
			)
		)
		(property "Manufacturer" ""
			(at 396.453002 319.4 0)
			(layer "F.Fab")
			(hide yes)
			(effects
				(font
					(size 1 1)
					(thickness 0.15)
				)
			)
		)
		(property ki_fp_filters "Net*Tie*")
		(sheetname "/Supply/")
		(sheetfile "supply.kicad_sch")
		(attr smd exclude_from_pos_files exclude_from_bom)
		(net_tie_pad_groups "1, 2")
		(fp_poly
			(pts
				(xy -0.0635 -0.0635) (xy 0.0625 -0.0635) (xy 0.0625 0.0635) (xy -0.0635 0.0635)
			)
			(stroke
				(width 0)
				(type solid)
			)
			(fill yes)
			(layer "F.Cu")
		)
		(pad "1" smd roundrect
			(at -0.127 0)
			(size 0.127 0.127)
			(layers "F.Cu")
			(roundrect_rratio 0.5)
			(chamfer_ratio 0)
			(chamfer top_left bottom_left)
			(net 175 "/Supply/1V1_SEN_-")
			(pinfunction "1")
			(pintype "passive")
		)
		(pad "2" smd roundrect
			(at 0.126 0 180)
			(size 0.127 0.127)
			(layers "F.Cu")
			(roundrect_rratio 0.5)
			(chamfer_ratio 0)
			(chamfer top_left bottom_left)
			(net 206 "+1V1")
			(pinfunction "2")
			(pintype "passive")
		)
	)
	(footprint "antmicro-footprints:C_0402_1005Metric"
		(layer "F.Cu")
		(at 199.203499 135.48 90)
		(descr "Capacitor SMD 0402")
		(tags "capacitor SMD 0402")
		(property "Reference" "C194"
			(at 0 -0.699 90)
			(layer "F.SilkS")
			(hide yes)
			(effects
				(font
					(size 0.7 0.7)
					(thickness 0.15)
				)
				(justify left bottom)
			)
		)
		(property "Value" "C_1u_0402"
			(at -1.022927 2.155213 90)
			(layer "F.Fab")
			(effects
				(font
					(size 0.7 0.7)
					(thickness 0.15)
				)
				(justify left bottom)
			)
		)
		(property "Datasheet" "https://product.tdk.com/en/search/capacitor/ceramic/mlcc/info?part_no=C1005X6S1A105K050BC"
			(at 0 0 90)
			(layer "F.Fab")
			(hide yes)
			(effects
				(font
					(size 1.27 1.27)
					(thickness 0.15)
				)
			)
		)
		(property "Author" "Antmicro"
			(at 334.683499 -63.723499 0)
			(layer "F.Fab")
			(hide yes)
			(effects
				(font
					(size 1 1)
					(thickness 0.15)
				)
			)
		)
		(property "Dielectric" ""
			(at 334.683499 -63.723499 0)
			(layer "F.Fab")
			(hide yes)
			(effects
				(font
					(size 1 1)
					(thickness 0.15)
				)
			)
		)
		(property "License" "Apache-2.0"
			(at 334.683499 -63.723499 0)
			(layer "F.Fab")
			(hide yes)
			(effects
				(font
					(size 1 1)
					(thickness 0.15)
				)
			)
		)
		(property "MPN" "C1005X6S1A105K050BC"
			(at 334.683499 -63.723499 0)
			(layer "F.Fab")
			(hide yes)
			(effects
				(font
					(size 1 1)
					(thickness 0.15)
				)
			)
		)
		(property "Manufacturer" "TDK"
			(at 334.683499 -63.723499 0)
			(layer "F.Fab")
			(hide yes)
			(effects
				(font
					(size 1 1)
					(thickness 0.15)
				)
			)
		)
		(property "Val" "1u"
			(at 334.683499 -63.723499 0)
			(layer "F.Fab")
			(hide yes)
			(effects
				(font
					(size 1 1)
					(thickness 0.15)
				)
			)
		)
		(property "Voltage" ""
			(at 334.683499 -63.723499 0)
			(layer "F.Fab")
			(hide yes)
			(effects
				(font
					(size 1 1)
					(thickness 0.15)
				)
			)
		)
		(sheetname "/Supply/")
		(sheetfile "supply.kicad_sch")
		(attr smd)
		(fp_rect
			(start -0.9659 -0.481258)
			(end 0.9649 0.458742)
			(stroke
				(width 0.05)
				(type solid)
			)
			(fill no)
			(layer "F.CrtYd")
		)
		(fp_line
			(start 0.499 -0.25)
			(end 0.499 0.248)
			(stroke
				(width 0.15)
				(type solid)
			)
			(layer "F.Fab")
		)
		(fp_line
			(start -0.499 -0.25)
			(end 0.499 -0.25)
			(stroke
				(width 0.15)
				(type solid)
			)
			(layer "F.Fab")
		)
		(fp_line
			(start 0.499 0.248)
			(end -0.499 0.248)
			(stroke
				(width 0.15)
				(type solid)
			)
			(layer "F.Fab")
		)
		(fp_line
			(start -0.499 0.248)
			(end -0.499 -0.25)
			(stroke
				(width 0.15)
				(type solid)
			)
			(layer "F.Fab")
		)
		(pad "1" smd roundrect
			(at -0.484 0 90)
			(size 0.59 0.64)
			(layers "F.Cu" "F.Mask" "F.Paste")
			(roundrect_rratio 0.25)
			(net 1 "GND")
			(pintype "passive")
		)
		(pad "2" smd roundrect
			(at 0.484 0 90)
			(size 0.59 0.64)
			(layers "F.Cu" "F.Mask" "F.Paste")
			(roundrect_rratio 0.25)
			(net 41 "+3V3_AON")
			(pintype "passive")
		)
	)
	(footprint "antmicro-footprints:R_0402_1005Metric"
		(layer "F.Cu")
		(at 185 164.951 -90)
		(descr "Resistor SMD 0402")
		(tags "resistor SMD 0402")
		(property "Reference" "R182"
			(at -1.122484 -0.772697 270)
			(layer "F.SilkS")
			(hide yes)
			(effects
				(font
					(size 0.7 0.7)
					(thickness 0.15)
				)
				(justify left bottom)
			)
		)
		(property "Value" "R_10k_0402"
			(at -1.011843 1.772047 270)
			(layer "F.Fab")
			(effects
				(font
					(size 0.7 0.7)
					(thickness 0.15)
				)
				(justify left bottom)
			)
		)
		(property "Datasheet" "https://www.bourns.com/docs/product-datasheets/cr.pdf"
			(at 0 0 270)
			(layer "F.Fab")
			(hide yes)
			(effects
				(font
					(size 1.27 1.27)
					(thickness 0.15)
				)
			)
		)
		(property "Author" "Antmicro"
			(at 20.049 349.951 0)
			(layer "F.Fab")
			(hide yes)
			(effects
				(font
					(size 1 1)
					(thickness 0.15)
				)
			)
		)
		(property "License" "Apache-2.0"
			(at 20.049 349.951 0)
			(layer "F.Fab")
			(hide yes)
			(effects
				(font
					(size 1 1)
					(thickness 0.15)
				)
			)
		)
		(property "MPN" "CR0402-FX-1002GLF"
			(at 20.049 349.951 0)
			(layer "F.Fab")
			(hide yes)
			(effects
				(font
					(size 1 1)
					(thickness 0.15)
				)
			)
		)
		(property "Manufacturer" "Bourns"
			(at 20.049 349.951 0)
			(layer "F.Fab")
			(hide yes)
			(effects
				(font
					(size 1 1)
					(thickness 0.15)
				)
			)
		)
		(property "Tolerance" "1%"
			(at 20.049 349.951 0)
			(layer "F.Fab")
			(hide yes)
			(effects
				(font
					(size 1 1)
					(thickness 0.15)
				)
			)
		)
		(property "Val" "10k"
			(at 20.049 349.951 0)
			(layer "F.Fab")
			(hide yes)
			(effects
				(font
					(size 1 1)
					(thickness 0.15)
				)
			)
		)
		(sheetname "/Supply/")
		(sheetfile "supply.kicad_sch")
		(attr smd)
		(fp_rect
			(start -0.93 -0.47)
			(end 0.93 0.47)
			(stroke
				(width 0.05)
				(type solid)
			)
			(fill no)
			(layer "F.CrtYd")
		)
		(fp_rect
			(start -0.5 -0.25)
			(end 0.5 0.25)
			(stroke
				(width 0.15)
				(type solid)
			)
			(fill no)
			(layer "F.Fab")
		)
		(pad "1" smd roundrect
			(at -0.485 0 270)
			(size 0.59 0.64)
			(layers "F.Cu" "F.Mask" "F.Paste")
			(roundrect_rratio 0.25)
			(net 200 "+3V3")
			(pintype "passive")
		)
		(pad "2" smd roundrect
			(at 0.485 0 270)
			(size 0.59 0.64)
			(layers "F.Cu" "F.Mask" "F.Paste")
			(roundrect_rratio 0.25)
			(net 386 "Net-(U30-~{PWRDN})")
			(pintype "passive")
		)
	)
)
